# BASEBOARD_FAB2 (Tioga Pass) — schematic parts with pin connectivity, parts 2327–2347 of 4751; source: Cadence DE-HDL packaged netlist (pstxprt.dat, pstxnet.dat, pstchip.dat)

FB2T3  HCB1608KF-800T30-GP  pkg DISCRET-G9  page 149 : 1 = P3V3_STBY ; 2 = VCC_ADCAV3V3
FB2T4  HCB1608KF-800T30-GP  pkg DISCRET-G9  page 149 : 1 = P3V3_STBY ; 2 = VCC_D_3V3
FB2T5  HCB1608KF-800T30-GP  pkg DISCRET-G9  page 149 : 1 = P3V3_STBY ; 2 = VCC_PA_3V3
FB2T7  HCB1608KF-800T30-GP  pkg DISCRET-G9  page 149 : 1 = P1V15_AUX_BMC ; 2 = VCC_A_1V1
FB3M1  FERRITE  120 FB  pkg SM  page 127 : 1 = P1V05_PCH_STBY ; 2 = P1V05_PCH_STBY_VCCA_PLL1
FB3M2  FERRITE  120 FB  pkg SM  page 127 : 1 = P1V05_PCH_STBY ; 2 = P1V05_PCH_STBY_VCCA_PLL0
FB3M3  FERRITE  120 FB  pkg SM  page 127 : 1 = P1V05_PCH_STBY ; 2 = P1V05_PCH_STBY_VCCA_XTAL
FB3M4  FERRITE  120 FB  pkg SM  page 127 : 1 = P1V05_PCH_STBY ; 2 = P1V05_PCH_STBY_ISCLK_PLL
FB4A1  FERRITE  22 1% FB  pkg SM  page 234 : 1 = P12V_STBY ; 2 = VR_FET_SW_P12V_STBY_PVPP_KLM
FB4G1  FERRITE  22 1% FB  pkg SM  page 233 : 1 = P12V_STBY ; 2 = VR_FET_SW_P12V_STBY_PVPP_GHJ
FB6P1  FERRITE  600 FB  pkg SMLF  page 102 : 1 = P3V3 ; 2 = P3V3_DB1200
FB7B1  FERRITE  22 1% FB  pkg SM  page 232 : 1 = P12V_STBY ; 2 = VR_FET_SW_P12V_STBY_PVPP_DEF
FB7E1  FERRITE  22 FB  pkg SM  page 241 : 1 = P12V_STBY ; 2 = VR_FET_SW_P5V_STBY_PVIN
FB7F1  FERRITE  22 1% FB  pkg SM  page 231 : 1 = P12V_STBY ; 2 = VR_FET_SW_P12V_STBY_PVPP_ABC
FB9E1  BLM31SN500SN1L-GP  pkg DISCRET-GB1  page 240 : 1 = P12V_STBY ; 2 = VR_FET_SW_P12V_STBY_P3V3_STBY
FB25W1  BLM15AG121SN-1GP  pkg DISCRET-G  page 254 : 1 = XDP_CPU_TCK0_R ; 2 = XDP_CPU_TCK0
FB25W2  BLM15AG121SN-1GP  pkg DISCRET-G  page 254 : 1 = XDP_PCH_TCK1_R ; 2 = XDP_PCH_TCK1
FB25W3  BLM15AG121SN-1GP  pkg DISCRET-G  page 254 : 1 = XDP_TRST_R_N ; 2 = XDP_TRST_N
FB25W4  BLM15AG121SN-1GP  pkg DISCRET-G  page 254 : 1 = XDP_TDI_R ; 2 = XDP_TDI
FB25W5  BLM15AG121SN-1GP  pkg DISCRET-G  page 254 : 1 = XDP_TMS_R ; 2 = XDP_TMS

J1A1  SCONN288_H44441004  SCONN  pkg PIP  page 87
  1  \12v\(1)  = P12V_NVDIMM_KLM
  2  VSS(93)  GROUND  = GND
  3  DQ(4)  BI  = M_M_DQ<5>
  4  VSS(92)  GROUND  = GND
  5  DQ(0)  BI  = M_M_DQ<1>
  6  VSS(91)  GROUND  = GND
  7  DQS9P  BI  = M_M_DQS_DP<9>
  8  DQS9N  BI  = M_M_DQS_DN<9>
  9  VSS(90)  GROUND  = GND
  10  DQ(6)  BI  = M_M_DQ<7>
  11  VSS(89)  GROUND  = GND
  12  DQ(2)  BI  = M_M_DQ<3>
  13  VSS(88)  GROUND  = GND
  14  DQ(12)  BI  = M_M_DQ<13>
  15  VSS(87)  GROUND  = GND
  16  DQ(8)  BI  = M_M_DQ<9>
  17  VSS(86)  GROUND  = GND
  18  DQS10P  BI  = M_M_DQS_DP<10>
  19  DQS10N  BI  = M_M_DQS_DN<10>
  20  VSS(85)  GROUND  = GND
  21  DQ(14)  BI  = M_M_DQ<15>
  22  VSS(84)  GROUND  = GND
  23  DQ(10)  BI  = M_M_DQ<11>
  24  VSS(83)  GROUND  = GND
  25  DQ(20)  BI  = M_M_DQ<21>
  26  VSS(82)  GROUND  = GND
  27  DQ(16)  BI  = M_M_DQ<17>
  28  VSS(81)  GROUND  = GND
  29  DQS11P  BI  = M_M_DQS_DP<11>
  30  DQS11N  BI  = M_M_DQS_DN<11>
  31  VSS(80)  GROUND  = GND
  32  DQ(22)  BI  = M_M_DQ<23>
  33  VSS(79)  GROUND  = GND
  34  DQ(18)  BI  = M_M_DQ<19>
  35  VSS(78)  GROUND  = GND
  36  DQ(28)  BI  = M_M_DQ<29>
  37  VSS(77)  GROUND  = GND
  38  DQ(24)  BI  = M_M_DQ<25>
  39  VSS(76)  GROUND  = GND
  40  DQS12P  BI  = M_M_DQS_DP<12>
  41  DQS12N  BI  = M_M_DQS_DN<12>
  42  VSS(75)  GROUND  = GND
  43  DQ(30)  BI  = M_M_DQ<31>
  44  VSS(74)  GROUND  = GND
  45  DQ(26)  BI  = M_M_DQ<27>
  46  VSS(73)  GROUND  = GND
  47  CB(4)  BI  = M_M_ECC<5>
  48  VSS(72)  GROUND  = GND
  49  CB(0)  BI  = M_M_ECC<1>
  50  VSS(71)  GROUND  = GND
  51  DQS17P  BI  = M_M_DQS_DP<17>
  52  DQS17N  BI  = M_M_DQS_DN<17>
  53  VSS(70)  GROUND  = GND
  54  CB(6)  BI  = M_M_ECC<7>
  55  VSS(69)  GROUND  = GND
  56  CB(2)  BI  = M_M_ECC<3>
  57  VSS(68)  GROUND  = GND
  58  RESET_N  BI  = M_KLM_RST_N
  59  VDD(25)  POWER  = PVDDQ_KLM
  60  CKE(0)  BI  = M_M_CKE<0>
  61  VDD(24)  POWER  = PVDDQ_KLM
  62  ACT_N  BI  = M_M_ACT_N
  63  BG(0)  BI  = M_M_BG<0>
  64  VDD(23)  POWER  = PVDDQ_KLM
  65  A12  BI  = M_M_MA<12>
  66  A9  BI  = M_M_MA<9>
  67  VDD(22)  POWER  = PVDDQ_KLM
  68  A8  BI  = M_M_MA<8>
  69  A6  BI  = M_M_MA<6>
  70  VDD(21)  POWER  = PVDDQ_KLM
  71  A3  BI  = M_M_MA<3>
  72  A1  BI  = M_M_MA<1>
  73  VDD(20)  POWER  = PVDDQ_KLM
  74  CK0P  BI  = M_M_CLK_DP<0>
  75  CK0N  BI  = M_M_CLK_DN<0>
  76  VDD(19)  POWER  = PVDDQ_KLM
  77  VTT(1)  POWER  = PVTT_KLM
  78  EVENT_N  BI  = FM_DIMM_EVENT_COD_N
  79  A0  BI  = M_M_MA<0>
  80  VDD(18)  POWER  = PVDDQ_KLM
  81  BA(0)  BI  = M_M_BA<0>
  82  A16_RAS_N  BI  = M_M_MA<16>
  83  VDD(17)  POWER  = PVDDQ_KLM
  84  S0_N  BI  = M_M_CS_N<0>
  85  VDD(16)  POWER  = PVDDQ_KLM
  86  A15_CAS_N  BI  = M_M_MA<15>
  87  ODT(0)  BI  = M_M_ODT<0>
  88  VDD(15)  POWER  = PVDDQ_KLM
  89  S1_N  BI  = M_M_CS_N<1>
  90  VDD(14)  POWER  = PVDDQ_KLM
  91  ODT(1)  BI  = M_M_ODT<1>
  92  VDD(13)  POWER  = PVDDQ_KLM
  93  S2_N_C(0)  BI  = M_M_CS_N<2>
  94  VSS(67)  GROUND  = GND
  95  DQ(36)  BI  = M_M_DQ<37>
  96  VSS(66)  GROUND  = GND
  97  DQ(32)  BI  = M_M_DQ<33>
  98  VSS(65)  GROUND  = GND
  99  DQS13P  BI  = M_M_DQS_DP<13>
  100  DQS13N  BI  = M_M_DQS_DN<13>
  101  VSS(64)  GROUND  = GND
  102  DQ(38)  BI  = M_M_DQ<39>
  103  VSS(63)  GROUND  = GND
  104  DQ(34)  BI  = M_M_DQ<35>
  105  VSS(62)  GROUND  = GND
  106  DQ(44)  BI  = M_M_DQ<45>
  107  VSS(61)  GROUND  = GND
  108  DQ(40)  BI  = M_M_DQ<41>
  109  VSS(60)  GROUND  = GND
  110  DQS14P  BI  = M_M_DQS_DP<14>
  111  DQS14N  BI  = M_M_DQS_DN<14>
  112  VSS(59)  GROUND  = GND
  113  DQ(46)  BI  = M_M_DQ<47>
  114  VSS(58)  GROUND  = GND
  115  DQ(42)  BI  = M_M_DQ<43>
  116  VSS(57)  GROUND  = GND
  117  DQ(52)  BI  = M_M_DQ<53>
  118  VSS(56)  GROUND  = GND
  119  DQ(48)  BI  = M_M_DQ<49>
  120  VSS(55)  GROUND  = GND
  121  DQS15P  BI  = M_M_DQS_DP<15>
  122  DQS15N  BI  = M_M_DQS_DN<15>
  123  VSS(54)  GROUND  = GND
  124  DQ(54)  BI  = M_M_DQ<55>
  125  VSS(53)  GROUND  = GND
  126  DQ(50)  BI  = M_M_DQ<51>
  127  VSS(52)  GROUND  = GND
  128  DQ(60)  BI  = M_M_DQ<61>
  129  VSS(51)  GROUND  = GND
  130  DQ(56)  BI  = M_M_DQ<57>
  131  VSS(50)  GROUND  = GND
  132  DQS16P  BI  = M_M_DQS_DP<16>
  133  DQS16N  BI  = M_M_DQS_DN<16>
  134  VSS(49)  GROUND  = GND
  135  DQ(62)  BI  = M_M_DQ<63>
  136  VSS(48)  GROUND  = GND
  137  DQ(58)  BI  = M_M_DQ<59>
  138  VSS(47)  GROUND  = GND
  139  SA(0)  BI  = GND
  140  SA(1)  BI  = GND
  141  SCL  BI  = SMB_DDR_KLM_VPP_SCL
  142  VPP(4)  POWER  = PVPP_KLM
  143  VPP(3)  POWER  = PVPP_KLM
  144  RFU(2)  BI  = TP_CH_M_DIMM_M0_RFU_2
  145  \12v\(0)  = P12V_NVDIMM_KLM
  146  VREFCA  BI  = M_M_VREF
  147  VSS(46)  GROUND  = GND
  148  DQ(5)  BI  = M_M_DQ<4>
  149  VSS(45)  GROUND  = GND
  150  DQ(1)  BI  = M_M_DQ<0>
  151  VSS(44)  GROUND  = GND
  152  DQS0N  BI  = M_M_DQS_DN<0>
  153  DQS0P  BI  = M_M_DQS_DP<0>
  154  VSS(43)  GROUND  = GND
  155  DQ(7)  BI  = M_M_DQ<6>
  156  VSS(42)  GROUND  = GND
  157  DQ(3)  BI  = M_M_DQ<2>
  158  VSS(41)  GROUND  = GND
  159  DQ(13)  BI  = M_M_DQ<12>
  160  VSS(40)  GROUND  = GND
  161  DQ(9)  BI  = M_M_DQ<8>
  162  VSS(39)  GROUND  = GND
  163  DQS1N  BI  = M_M_DQS_DN<1>
  164  DQS1P  BI  = M_M_DQS_DP<1>
  165  VSS(38)  GROUND  = GND
  166  DQ(15)  BI  = M_M_DQ<14>
  167  VSS(37)  GROUND  = GND
  168  DQ(11)  BI  = M_M_DQ<10>
  169  VSS(36)  GROUND  = GND
  170  DQ(21)  BI  = M_M_DQ<20>
  171  VSS(35)  GROUND  = GND
  172  DQ(17)  BI  = M_M_DQ<16>
  173  VSS(34)  GROUND  = GND
  174  DQS2N  BI  = M_M_DQS_DN<2>
  175  DQS2P  BI  = M_M_DQS_DP<2>
  176  VSS(33)  GROUND  = GND
  177  DQ(23)  BI  = M_M_DQ<22>
  178  VSS(32)  GROUND  = GND
  179  DQ(19)  BI  = M_M_DQ<18>
  180  VSS(31)  GROUND  = GND
  181  DQ(29)  BI  = M_M_DQ<28>
  182  VSS(30)  GROUND  = GND
  183  DQ(25)  BI  = M_M_DQ<24>
  184  VSS(29)  GROUND  = GND
  185  DQS3N  BI  = M_M_DQS_DN<3>
  186  DQS3P  BI  = M_M_DQS_DP<3>
  187  VSS(28)  GROUND  = GND
  188  DQ(31)  BI  = M_M_DQ<30>
  189  VSS(27)  GROUND  = GND
  190  DQ(27)  BI  = M_M_DQ<26>
  191  VSS(26)  GROUND  = GND
  192  CB(5)  BI  = M_M_ECC<4>
  193  VSS(25)  GROUND  = GND
  194  CB(1)  BI  = M_M_ECC<0>
  195  VSS(24)  GROUND  = GND
  196  DQS8N  BI  = M_M_DQS_DN<8>
  197  DQS8P  BI  = M_M_DQS_DP<8>
  198  VSS(23)  GROUND  = GND
  199  CB(7)  BI  = M_M_ECC<6>
  200  VSS(22)  GROUND  = GND
  201  CB(3)  BI  = M_M_ECC<2>
  202  VSS(21)  GROUND  = GND
  203  CKE(1)  BI  = M_M_CKE<1>
  204  VDD(12)  POWER  = PVDDQ_KLM
  205  RFU(0)  BI  = TP_CH_M_DIMM_M0_RFU_0
  206  VDD(11)  POWER  = PVDDQ_KLM
  207  BG(1)  BI  = M_M_BG<1>
  208  ALERT_N  BI  = M_M_ALERT_N
  209  VDD(10)  POWER  = PVDDQ_KLM
  210  A11  BI  = M_M_MA<11>
  211  A7  BI  = M_M_MA<7>
  212  VDD(9)  POWER  = PVDDQ_KLM
  213  A5  BI  = M_M_MA<5>
  214  A4  BI  = M_M_MA<4>
  215  VDD(8)  POWER  = PVDDQ_KLM
  216  A2  BI  = M_M_MA<2>
  217  VDD(7)  POWER  = PVDDQ_KLM
  218  CK1P  BI  = M_M_CLK_DP<1>
  219  CK1N  BI  = M_M_CLK_DN<1>
  220  VDD(6)  POWER  = PVDDQ_KLM
  221  VTT(0)  POWER  = PVTT_KLM
  222  PAR  BI  = M_M_PAR
  223  VDD(5)  POWER  = PVDDQ_KLM
  224  BA(1)  BI  = M_M_BA<1>
  225  A10  BI  = M_M_MA<10>
  226  VDD(4)  POWER  = PVDDQ_KLM
  227  RFU(1)  BI  = TP_CH_M_DIMM_M0_RFU_1
  228  A14_WE_N  BI  = M_M_MA<14>
  229  VDD(3)  POWER  = PVDDQ_KLM
  230  SAVE_N_NC  BI  = FM_ADR_COMPLETE_KLM_N
  231  VDD(2)  POWER  = PVDDQ_KLM
  232  A13  BI  = M_M_MA<13>
  233  VDD(1)  POWER  = PVDDQ_KLM
  234  A17  BI  = M_M_MA<17>
  235  C(2)  BI  = M_M_C<2>
  236  VDD(0)  POWER  = PVDDQ_KLM
  237  S3_N_C(1)  BI  = M_M_CS_N<3>
  238  SA(2)  BI  = PVPP_KLM
  239  VSS(20)  GROUND  = GND
  240  DQ(37)  BI  = M_M_DQ<36>
  241  VSS(19)  GROUND  = GND
  242  DQ(33)  BI  = M_M_DQ<32>
  243  VSS(18)  GROUND  = GND
  244  DQS4N  BI  = M_M_DQS_DN<4>
  245  DQS4P  BI  = M_M_DQS_DP<4>
  246  VSS(17)  GROUND  = GND
  247  DQ(39)  BI  = M_M_DQ<38>
  248  VSS(16)  GROUND  = GND
  249  DQ(35)  BI  = M_M_DQ<34>
  250  VSS(15)  GROUND  = GND
  251  DQ(45)  BI  = M_M_DQ<44>
  252  VSS(14)  GROUND  = GND
  253  DQ(41)  BI  = M_M_DQ<40>
  254  VSS(13)  GROUND  = GND
  255  DQS5N  BI  = M_M_DQS_DN<5>
  256  DQS5P  BI  = M_M_DQS_DP<5>
  257  VSS(12)  GROUND  = GND
  258  DQ(47)  BI  = M_M_DQ<46>
  259  VSS(11)  GROUND  = GND
  260  DQ(43)  BI  = M_M_DQ<42>
  261  VSS(10)  GROUND  = GND
  262  DQ(53)  BI  = M_M_DQ<52>
  263  VSS(9)  GROUND  = GND
  264  DQ(49)  BI  = M_M_DQ<48>
  265  VSS(8)  GROUND  = GND
  266  DQS6N  BI  = M_M_DQS_DN<6>
  267  DQS6P  BI  = M_M_DQS_DP<6>
  268  VSS(7)  GROUND  = GND
  269  DQ(55)  BI  = M_M_DQ<54>
  270  VSS(6)  GROUND  = GND
  271  DQ(51)  BI  = M_M_DQ<50>
  272  VSS(5)  GROUND  = GND
  273  DQ(61)  BI  = M_M_DQ<60>
  274  VSS(4)  GROUND  = GND
  275  DQ(57)  BI  = M_M_DQ<56>
  276  VSS(3)  GROUND  = GND
  277  DQS7N  BI  = M_M_DQS_DN<7>
  278  DQS7P  BI  = M_M_DQS_DP<7>
  279  VSS(2)  GROUND  = GND
  280  DQ(63)  BI  = M_M_DQ<62>
  281  VSS(1)  GROUND  = GND
  282  DQ(59)  BI  = M_M_DQ<58>
  283  VSS(0)  GROUND  = GND
  284  VDDSPD  BI  = PVPP_KLM
  285  SDA  BI  = SMB_DDR_KLM_VPP_SDA
  286  VPP(1)  POWER  = PVPP_KLM
  287  VPP(0)  POWER  = PVPP_KLM
  288  VPP(2)  POWER  = PVPP_KLM
